# T6G (Grand Teton) — schematic netlist excerpt (pin names and nets, part order shuffled) for the footprints in the layout excerpt that follows; sources: Cadence DE-HDL packaged netlist, KiCad conversion of 04192023_DAF0TMB3IC0_F0TG_MB_C_brd_V02_OCP.brd

PU42  RAA229620GNPHA0  RAA229620GNP#HA0 IC  pkg QFN48_TH_0-4_6X6XH  page 193
  PWM0  = PVDDCR_SOC_P0_PWM1
  PWM1  = PVDDCR_SOC_P0_PWM2
  PWM2  = PVDDCR_SOC_P0_PWM3
  PWM3  = NC_PVDDCR_CPU0_P0_PWM9
  PWM4  = NC_PVDDCR_CPU0_P0_PWM8
  PWM5  = NC_PVDDCR_CPU0_P0_PWM7
  PWM6  = PVDDCR_CPU0_P0_PWM6
  PWM7  = PVDDCR_CPU0_P0_PWM5
  PWM8  = PVDDCR_CPU0_P0_PWM4
  PWM9  = PVDDCR_CPU0_P0_PWM3
  PWM10  = PVDDCR_CPU0_P0_PWM2
  PWM11  = PVDDCR_CPU0_P0_PWM1
  PMSDA  = PVDDCR_CPU0_P0_PMSDA_R
  PMSCL  = PVDDCR_CPU0_P0_PMSCL_R
  NPMALERT  = PVDDCR_CPU0_P0_PMALERT_R
  PG0  = PWRGD_PVDDCR_CPU0_P0_R
  EN0  = PVDDCR_CPU0_P0_EN_R
  RESET_L  = PVDDCR_CPU0_P0_RESET_N_R
  VDDIO  = PVDD18_S5_P0
  PG1  = PWRGD_PVDDCR_SOC_P0_R
  SVD  = SVID_PVDDCR_CPU0_P0_SVD_R1
  SVC  = SVID_PVDDCR_CPU0_P0_SVC_R1
  SVTO  = SVID_PVDDCR_CPU0_P0_SVTO_R
  SVTI  = SVID_PVDDCR_CPU0_P0_SVTI_R
  VSEN0  = VSENSE_PVDDCR_CPU0_P0_VSEN0
  RGND0  = VSENSE_VSS_SENSE_A_P0
  CS11  = PVDDCR_CPU0_P0_IMON1
  CS10  = PVDDCR_CPU0_P0_IMON2
  CS9  = PVDDCR_CPU0_P0_IMON3
  CS8  = PVDDCR_CPU0_P0_IMON4
  CS7  = PVDDCR_CPU0_P0_IMON5
  CS6  = PVDDCR_CPU0_P0_IMON6
  CS5  = NC_PVDDCR_CPU0_P0_IMON7
  CS4  = NC_PVDDCR_CPU0_P0_IMON8
  CS3  = NC_PVDDCR_CPU0_P0_IMON9
  CS2  = PVDDCR_SOC_P0_IMON3
  CS1  = PVDDCR_SOC_P0_IMON2
  CS0  = PVDDCR_SOC_P0_IMON1
  RGND1  = VSENSE_VSS_SENSE_A_P0
  VSEN1  = VSENSE_PVDDCR_SOC_P0_VSEN1
  OCP_L  = PVDDCR_CPU0_P0_OCP_N_R
  \en1||addr_cfg\  = PVDDCR_SOC_P0_EN//ADDR_CFG
  TEMP1  = PVDDCR_SOC_P0_TEMP1
  TEMP0  = PVDDCR_CPU0_P0_TEMP0
  \vmon||iinsen\  = PVDDCR_CPU0_P0_VMON
  VINSEN  = PVDDCR_CPU0_P0_VINSEN
  VCC  = PVDDCR_CPU0_P0_VCC
  VCCS  = PVDDCR_CPU0_P0_VCCS
  TH_GND  = GND

(kicad_pcb
	(version 20260206)
	(generator "pcbnew")
	(generator_version "10.0")
	(general
		(thickness 1.6)
		(legacy_teardrops no)
	)
	(paper "A4")
	(title_block
		(title "04192023_DAF0TMB3IC0_F0TG_MB_C_brd_V02_OCP.brd")
		(comment 1 "Grand Teton / footprint 5338 of 8354 (PU42), pads 1-41 of 49")
	)
	(layers
		(0 "F.Cu" signal "TOP")
		(4 "In1.Cu" signal "GND")
		(6 "In2.Cu" signal "IN1")
		(8 "In3.Cu" signal "GND1")
		(10 "In4.Cu" signal "IN2")
		(12 "In5.Cu" signal "GND2")
		(14 "In6.Cu" signal "IN3")
		(16 "In7.Cu" signal "GND3")
		(18 "In8.Cu" signal "VCC")
		(20 "In9.Cu" signal "VCC1")
		(22 "In10.Cu" signal "GND4")
		(24 "In11.Cu" signal "IN4")
		(26 "In12.Cu" signal "GND5")
		(28 "In13.Cu" signal "IN5")
		(30 "In14.Cu" signal "GND6")
		(32 "In15.Cu" signal "IN6")
		(34 "In16.Cu" signal "GND7")
		(2 "B.Cu" signal "BOTTOM")
		(9 "F.Adhes" user "F.Adhesive")
		(11 "B.Adhes" user "B.Adhesive")
		(13 "F.Paste" user "Package Geometry/Pastemask Top")
		(15 "B.Paste" user "Package Geometry/Pastemask Bottom")
		(5 "F.SilkS" user "Ref Des/Silkscreen Top")
		(7 "B.SilkS" user "Ref Des/Silkscreen Bottom")
		(1 "F.Mask" user "Board Geometry/Soldermask Top")
		(3 "B.Mask" user "Board Geometry/Soldermask Bottom")
		(17 "Dwgs.User" user "User.Drawings")
		(19 "Cmts.User" user "User.Comments")
		(21 "Eco1.User" user "User.Eco1")
		(23 "Eco2.User" user "User.Eco2")
		(25 "Edge.Cuts" user "Board Geometry/Outline")
		(27 "Margin" user)
		(31 "F.CrtYd" user "Package Geometry/Place Bound Top")
		(29 "B.CrtYd" user "Package Geometry/Place Bound Bottom")
		(35 "F.Fab" user "Ref Des/Assembly Top")
		(33 "B.Fab" user "Ref Des/Assembly Bottom")
	)
	(footprint ""
		(layer "B.Cu")
		(at 378.398278 -142.361158 -90)
		(property "Reference" "PU42"
			(at 5.846572 1.250696 0)
			(unlocked yes)
			(layer "B.SilkS")
			(effects
				(font
					(size 0.7874 0.5842)
					(thickness 0.1524)
				)
				(justify mirror)
			)
		)
		(property "Value" ""
			(at 0 0 90)
			(layer "B.Fab")
			(effects
				(font
					(size 1.27 1.27)
				)
				(justify mirror)
			)
		)
		(duplicate_pad_numbers_are_jumpers no)
		(pad "1" smd rect
			(at 2.875026 -2.199894 180)
			(size 0.1778 0.6604)
			(layers "B.Cu" "B.Mask" "B.Paste")
			(net "PVDDCR_SOC_P0_PWM1")
		)
		(pad "2" smd rect
			(at 2.875026 -1.800098 180)
			(size 0.1778 0.6604)
			(layers "B.Cu" "B.Mask" "B.Paste")
			(net "PVDDCR_SOC_P0_PWM2")
		)
		(pad "3" smd rect
			(at 2.875026 -1.400048 180)
			(size 0.1778 0.6604)
			(layers "B.Cu" "B.Mask" "B.Paste")
			(net "PVDDCR_SOC_P0_PWM3")
		)
		(pad "4" smd rect
			(at 2.875026 -0.999998 180)
			(size 0.1778 0.6604)
			(layers "B.Cu" "B.Mask" "B.Paste")
			(net "NC_PVDDCR_CPU0_P0_PWM9")
		)
		(pad "5" smd rect
			(at 2.875026 -0.599948 180)
			(size 0.1778 0.6604)
			(layers "B.Cu" "B.Mask" "B.Paste")
			(net "NC_PVDDCR_CPU0_P0_PWM8")
		)
		(pad "6" smd rect
			(at 2.875026 -0.199898 180)
			(size 0.1778 0.6604)
			(layers "B.Cu" "B.Mask" "B.Paste")
			(net "NC_PVDDCR_CPU0_P0_PWM7")
		)
		(pad "7" smd rect
			(at 2.875026 0.199898 180)
			(size 0.1778 0.6604)
			(layers "B.Cu" "B.Mask" "B.Paste")
			(net "PVDDCR_CPU0_P0_PWM6")
		)
		(pad "8" smd rect
			(at 2.875026 0.599948 180)
			(size 0.1778 0.6604)
			(layers "B.Cu" "B.Mask" "B.Paste")
			(net "PVDDCR_CPU0_P0_PWM5")
		)
		(pad "9" smd rect
			(at 2.875026 0.999998 180)
			(size 0.1778 0.6604)
			(layers "B.Cu" "B.Mask" "B.Paste")
			(net "PVDDCR_CPU0_P0_PWM4")
		)
		(pad "10" smd rect
			(at 2.875026 1.400048 180)
			(size 0.1778 0.6604)
			(layers "B.Cu" "B.Mask" "B.Paste")
			(net "PVDDCR_CPU0_P0_PWM3")
		)
		(pad "11" smd rect
			(at 2.875026 1.800098 180)
			(size 0.1778 0.6604)
			(layers "B.Cu" "B.Mask" "B.Paste")
			(net "PVDDCR_CPU0_P0_PWM2")
		)
		(pad "12" smd rect
			(at 2.875026 2.199894 180)
			(size 0.1778 0.6604)
			(layers "B.Cu" "B.Mask" "B.Paste")
			(net "PVDDCR_CPU0_P0_PWM1")
		)
		(pad "13" smd rect
			(at 2.199894 2.875026 90)
			(size 0.1778 0.6604)
			(layers "B.Cu" "B.Mask" "B.Paste")
			(net "PVDDCR_CPU0_P0_PMSDA_R")
		)
		(pad "14" smd rect
			(at 1.800098 2.875026 90)
			(size 0.1778 0.6604)
			(layers "B.Cu" "B.Mask" "B.Paste")
			(net "PVDDCR_CPU0_P0_PMSCL_R")
		)
		(pad "15" smd rect
			(at 1.400048 2.875026 90)
			(size 0.1778 0.6604)
			(layers "B.Cu" "B.Mask" "B.Paste")
			(net "PVDDCR_CPU0_P0_PMALERT_R")
		)
		(pad "16" smd rect
			(at 0.999998 2.875026 90)
			(size 0.1778 0.6604)
			(layers "B.Cu" "B.Mask" "B.Paste")
			(net "PWRGD_PVDDCR_CPU0_P0_R")
		)
		(pad "17" smd rect
			(at 0.599948 2.875026 90)
			(size 0.1778 0.6604)
			(layers "B.Cu" "B.Mask" "B.Paste")
			(net "PVDDCR_CPU0_P0_EN_R")
		)
		(pad "18" smd rect
			(at 0.199898 2.875026 90)
			(size 0.1778 0.6604)
			(layers "B.Cu" "B.Mask" "B.Paste")
			(net "PVDDCR_CPU0_P0_RESET_N_R")
		)
		(pad "19" smd rect
			(at -0.199898 2.875026 90)
			(size 0.1778 0.6604)
			(layers "B.Cu" "B.Mask" "B.Paste")
			(net "PVDD18_S5_P0")
		)
		(pad "20" smd rect
			(at -0.599948 2.875026 90)
			(size 0.1778 0.6604)
			(layers "B.Cu" "B.Mask" "B.Paste")
			(net "PWRGD_PVDDCR_SOC_P0_R")
		)
		(pad "21" smd rect
			(at -0.999998 2.875026 90)
			(size 0.1778 0.6604)
			(layers "B.Cu" "B.Mask" "B.Paste")
			(net "SVID_PVDDCR_CPU0_P0_SVD_R1")
		)
		(pad "22" smd rect
			(at -1.400048 2.875026 90)
			(size 0.1778 0.6604)
			(layers "B.Cu" "B.Mask" "B.Paste")
			(net "SVID_PVDDCR_CPU0_P0_SVC_R1")
		)
		(pad "23" smd rect
			(at -1.800098 2.875026 90)
			(size 0.1778 0.6604)
			(layers "B.Cu" "B.Mask" "B.Paste")
			(net "SVID_PVDDCR_CPU0_P0_SVTO_R")
		)
		(pad "24" smd rect
			(at -2.199894 2.875026 90)
			(size 0.1778 0.6604)
			(layers "B.Cu" "B.Mask" "B.Paste")
			(net "SVID_PVDDCR_CPU0_P0_SVTI_R")
		)
		(pad "25" smd rect
			(at -2.875026 2.199894 180)
			(size 0.1778 0.6604)
			(layers "B.Cu" "B.Mask" "B.Paste")
			(net "VSENSE_PVDDCR_CPU0_P0_VSEN0")
		)
		(pad "26" smd rect
			(at -2.875026 1.800098 180)
			(size 0.1778 0.6604)
			(layers "B.Cu" "B.Mask" "B.Paste")
			(net "VSENSE_VSS_SENSE_A_P0")
		)
		(pad "27" smd rect
			(at -2.875026 1.400048 180)
			(size 0.1778 0.6604)
			(layers "B.Cu" "B.Mask" "B.Paste")
			(net "PVDDCR_CPU0_P0_IMON1")
		)
		(pad "28" smd rect
			(at -2.875026 0.999998 180)
			(size 0.1778 0.6604)
			(layers "B.Cu" "B.Mask" "B.Paste")
			(net "PVDDCR_CPU0_P0_IMON2")
		)
		(pad "29" smd rect
			(at -2.875026 0.599948 180)
			(size 0.1778 0.6604)
			(layers "B.Cu" "B.Mask" "B.Paste")
			(net "PVDDCR_CPU0_P0_IMON3")
		)
		(pad "30" smd rect
			(at -2.875026 0.199898 180)
			(size 0.1778 0.6604)
			(layers "B.Cu" "B.Mask" "B.Paste")
			(net "PVDDCR_CPU0_P0_IMON4")
		)
		(pad "31" smd rect
			(at -2.875026 -0.199898 180)
			(size 0.1778 0.6604)
			(layers "B.Cu" "B.Mask" "B.Paste")
			(net "PVDDCR_CPU0_P0_IMON5")
		)
		(pad "32" smd rect
			(at -2.875026 -0.599948 180)
			(size 0.1778 0.6604)
			(layers "B.Cu" "B.Mask" "B.Paste")
			(net "PVDDCR_CPU0_P0_IMON6")
		)
		(pad "33" smd rect
			(at -2.875026 -0.999998 180)
			(size 0.1778 0.6604)
			(layers "B.Cu" "B.Mask" "B.Paste")
			(net "NC_PVDDCR_CPU0_P0_IMON7")
		)
		(pad "34" smd rect
			(at -2.875026 -1.400048 180)
			(size 0.1778 0.6604)
			(layers "B.Cu" "B.Mask" "B.Paste")
			(net "NC_PVDDCR_CPU0_P0_IMON8")
		)
		(pad "35" smd rect
			(at -2.875026 -1.800098 180)
			(size 0.1778 0.6604)
			(layers "B.Cu" "B.Mask" "B.Paste")
			(net "NC_PVDDCR_CPU0_P0_IMON9")
		)
		(pad "36" smd rect
			(at -2.875026 -2.199894 180)
			(size 0.1778 0.6604)
			(layers "B.Cu" "B.Mask" "B.Paste")
			(net "PVDDCR_SOC_P0_IMON3")
		)
		(pad "37" smd rect
			(at -2.199894 -2.875026 90)
			(size 0.1778 0.6604)
			(layers "B.Cu" "B.Mask" "B.Paste")
			(net "PVDDCR_SOC_P0_IMON2")
		)
		(pad "38" smd rect
			(at -1.800098 -2.875026 90)
			(size 0.1778 0.6604)
			(layers "B.Cu" "B.Mask" "B.Paste")
			(net "PVDDCR_SOC_P0_IMON1")
		)
		(pad "39" smd rect
			(at -1.400048 -2.875026 90)
			(size 0.1778 0.6604)
			(layers "B.Cu" "B.Mask" "B.Paste")
			(net "VSENSE_VSS_SENSE_A_P0")
		)
		(pad "40" smd rect
			(at -0.999998 -2.875026 90)
			(size 0.1778 0.6604)
			(layers "B.Cu" "B.Mask" "B.Paste")
			(net "VSENSE_PVDDCR_SOC_P0_VSEN1")
		)
		(pad "41" smd rect
			(at -0.599948 -2.875026 90)
			(size 0.1778 0.6604)
			(layers "B.Cu" "B.Mask" "B.Paste")
			(net "PVDDCR_CPU0_P0_OCP_N_R")
		)
	)
)
